(kicad_pcb
	(version 20260206)
	(generator "pcbnew")
	(generator_version "10.0")
	(general
		(thickness 1.6)
		(legacy_teardrops no)
	)
	(paper "A4")
	(title_block
		(title "03242023_DA0F0TMBIJ0_F0T_Motherboard_J_brd_V01_OCP.brd")
		(comment 1 "Grand Teton / footprints 4741-4747 of 6105")
	)
	(layers
		(0 "F.Cu" signal "TOP")
		(4 "In1.Cu" signal "GND")
		(6 "In2.Cu" signal "IN1")
		(8 "In3.Cu" signal "GND1")
		(10 "In4.Cu" signal "IN2")
		(12 "In5.Cu" signal "GND2")
		(14 "In6.Cu" signal "IN3")
		(16 "In7.Cu" signal "GND3")
		(18 "In8.Cu" signal "VCC")
		(20 "In9.Cu" signal "VCC1")
		(22 "In10.Cu" signal "GND4")
		(24 "In11.Cu" signal "IN4")
		(26 "In12.Cu" signal "GND5")
		(28 "In13.Cu" signal "IN5")
		(30 "In14.Cu" signal "GND6")
		(32 "In15.Cu" signal "IN6")
		(34 "In16.Cu" signal "GND7")
		(2 "B.Cu" signal "BOTTOM")
		(9 "F.Adhes" user "F.Adhesive")
		(11 "B.Adhes" user "B.Adhesive")
		(13 "F.Paste" user "Package Geometry/Pastemask Top")
		(15 "B.Paste" user "Package Geometry/Pastemask Bottom")
		(5 "F.SilkS" user "Ref Des/Silkscreen Top")
		(7 "B.SilkS" user "Ref Des/Silkscreen Bottom")
		(1 "F.Mask" user "Board Geometry/Soldermask Top")
		(3 "B.Mask" user "Board Geometry/Soldermask Bottom")
		(17 "Dwgs.User" user "User.Drawings")
		(19 "Cmts.User" user "User.Comments")
		(21 "Eco1.User" user "User.Eco1")
		(23 "Eco2.User" user "User.Eco2")
		(25 "Edge.Cuts" user "Board Geometry/Outline")
		(27 "Margin" user)
		(31 "F.CrtYd" user "Package Geometry/Place Bound Top")
		(29 "B.CrtYd" user "Package Geometry/Place Bound Bottom")
		(35 "F.Fab" user "Ref Des/Assembly Top")
		(33 "B.Fab" user "Ref Des/Assembly Bottom")
	)
	(footprint ""
		(layer "B.Cu")
		(at 493.36833 2.324608 90)
		(property "Reference" "X30"
			(at 1.283208 3.38328 270)
			(unlocked yes)
			(layer "B.SilkS")
			(effects
				(font
					(size 0.7874 0.5842)
					(thickness 0.1524)
				)
				(justify left mirror)
			)
		)
		(property "Value" ""
			(at 0 0 90)
			(layer "B.Fab")
			(effects
				(font
					(size 1.27 1.27)
				)
				(justify mirror)
			)
		)
		(property "Device Type" "TP_TDR_4P_FTS_TH-TP_TDR_4P_DIPA"
			(at -1.30175 1.27 0)
			(unlocked yes)
			(layer "B.Fab")
			(hide yes)
			(effects
				(font
					(size 0.635 0.4064)
					(thickness 0.1524)
				)
				(justify mirror)
			)
		)
		(property "User Part Number" "N_A"
			(at -1.30175 1.27 0)
			(unlocked yes)
			(layer "Cmts.User")
			(hide yes)
			(effects
				(font
					(size 0.635 0.4064)
					(thickness 0.1524)
				)
				(justify mirror)
			)
		)
		(duplicate_pad_numbers_are_jumpers no)
		(fp_line
			(start 0 -1.27)
			(end 0 -0.635)
			(stroke
				(width 0.1524)
				(type default)
			)
			(layer "B.SilkS")
		)
		(fp_line
			(start -2.54 -1.27)
			(end 0 -1.27)
			(stroke
				(width 0.1524)
				(type default)
			)
			(layer "B.SilkS")
		)
		(fp_line
			(start -2.54 -1.1303)
			(end -2.54 -1.27)
			(stroke
				(width 0.1524)
				(type default)
			)
			(layer "B.SilkS")
		)
		(fp_line
			(start 0 0.635)
			(end 0 1.905)
			(stroke
				(width 0.1524)
				(type default)
			)
			(layer "B.SilkS")
		)
		(fp_line
			(start -2.54 1.4097)
			(end -2.54 1.1303)
			(stroke
				(width 0.1524)
				(type default)
			)
			(layer "B.SilkS")
		)
		(fp_line
			(start 0 3.175)
			(end 0 3.81)
			(stroke
				(width 0.1524)
				(type default)
			)
			(layer "B.SilkS")
		)
		(fp_line
			(start 0 3.81)
			(end -2.54 3.81)
			(stroke
				(width 0.1524)
				(type default)
			)
			(layer "B.SilkS")
		)
		(fp_line
			(start -2.54 3.81)
			(end -2.54 3.6703)
			(stroke
				(width 0.1524)
				(type default)
			)
			(layer "B.SilkS")
		)
		(fp_poly
			(pts
				(xy 2.285746 -0.762) (xy 2.285746 0.762) (xy 0.761746 0)
			)
			(stroke
				(width 0)
				(type default)
			)
			(fill yes)
			(layer "B.SilkS")
		)
		(fp_line
			(start 0 -1.27)
			(end 0 3.81)
			(stroke
				(width 0.1)
				(type default)
			)
			(layer "B.Fab")
		)
		(fp_line
			(start -2.54 -1.27)
			(end 0 -1.27)
			(stroke
				(width 0.1)
				(type default)
			)
			(layer "B.Fab")
		)
		(fp_line
			(start 0 3.81)
			(end -2.54 3.81)
			(stroke
				(width 0.1)
				(type default)
			)
			(layer "B.Fab")
		)
		(fp_line
			(start -2.54 3.81)
			(end -2.54 -1.27)
			(stroke
				(width 0.1)
				(type default)
			)
			(layer "B.Fab")
		)
		(fp_poly
			(pts
				(xy 0.761746 0) (xy 2.285746 -0.762) (xy 2.285746 0.762)
			)
			(stroke
				(width 0)
				(type default)
			)
			(fill yes)
			(layer "B.Fab")
		)
		(pad "1" thru_hole circle
			(at 0 0 270)
			(size 1.0033 1.0033)
			(drill 0.249936)
			(layers "*.Cu" "*.Mask")
			(remove_unused_layers no)
			(net "TDR_DIFF_100_IN6_DP")
			(clearance 0.10795)
			(padstack
				(mode front_inner_back)
				(layer "Inner"
					(shape circle)
					(size 0.8001 0.8001)
					(clearance 0.1524)
				)
				(layer "B.Cu"
					(shape circle)
					(size 1.0033 1.0033)
					(thermal_gap 0.10795)
					(clearance 0.10795)
				)
			)
		)
		(pad "2" thru_hole circle
			(at -2.54 0 270)
			(size 1.9939 1.9939)
			(drill 0.249936)
			(layers "*.Cu" "*.Mask")
			(remove_unused_layers no)
			(net "T1_GND")
			(clearance 0.10795)
			(padstack
				(mode front_inner_back)
				(layer "Inner"
					(shape circle)
					(size 0.8001 0.8001)
					(clearance 0.1524)
				)
				(layer "B.Cu"
					(shape circle)
					(size 1.9939 1.9939)
					(thermal_gap 0.10795)
					(clearance 0.10795)
				)
			)
		)
		(pad "3" thru_hole circle
			(at -2.54 2.54 270)
			(size 1.9939 1.9939)
			(drill 0.249936)
			(layers "*.Cu" "*.Mask")
			(remove_unused_layers no)
			(net "T1_GND")
			(clearance 0.10795)
			(padstack
				(mode front_inner_back)
				(layer "Inner"
					(shape circle)
					(size 0.8001 0.8001)
					(clearance 0.1524)
				)
				(layer "B.Cu"
					(shape circle)
					(size 1.9939 1.9939)
					(thermal_gap 0.10795)
					(clearance 0.10795)
				)
			)
		)
		(pad "4" thru_hole circle
			(at 0 2.54 270)
			(size 1.0033 1.0033)
			(drill 0.249936)
			(layers "*.Cu" "*.Mask")
			(remove_unused_layers no)
			(net "TDR_DIFF_100_IN6_DN")
			(clearance 0.10795)
			(padstack
				(mode front_inner_back)
				(layer "Inner"
					(shape circle)
					(size 0.8001 0.8001)
					(clearance 0.1524)
				)
				(layer "B.Cu"
					(shape circle)
					(size 1.0033 1.0033)
					(thermal_gap 0.10795)
					(clearance 0.10795)
				)
			)
		)
	)
	(footprint ""
		(layer "B.Cu")
		(at 118.370604 -294.01008)
		(property "Reference" "C345"
			(at 0 0 0)
			(layer "B.SilkS")
			(hide yes)
			(effects
				(font
					(size 1.27 1.27)
				)
				(justify mirror)
			)
		)
		(property "Value" ""
			(at 0 0 0)
			(layer "B.Fab")
			(effects
				(font
					(size 1.27 1.27)
				)
				(justify mirror)
			)
		)
		(duplicate_pad_numbers_are_jumpers no)
		(fp_line
			(start -1.524 -0.762)
			(end -1.524 0.762)
			(stroke
				(width 0.1524)
				(type default)
			)
			(layer "B.SilkS")
		)
		(fp_line
			(start -1.524 0.762)
			(end 1.524 0.762)
			(stroke
				(width 0.1524)
				(type default)
			)
			(layer "B.SilkS")
		)
		(fp_line
			(start 1.524 -0.762)
			(end -1.524 -0.762)
			(stroke
				(width 0.1524)
				(type default)
			)
			(layer "B.SilkS")
		)
		(fp_line
			(start 1.524 0.762)
			(end 1.524 -0.762)
			(stroke
				(width 0.1524)
				(type default)
			)
			(layer "B.SilkS")
		)
		(fp_line
			(start -1.1049 -0.724916)
			(end 1.1049 -0.724916)
			(stroke
				(width 0.1)
				(type default)
			)
			(layer "B.Fab")
		)
		(fp_line
			(start -1.1049 0.724916)
			(end -1.1049 -0.724916)
			(stroke
				(width 0.1)
				(type default)
			)
			(layer "B.Fab")
		)
		(fp_line
			(start 1.1049 -0.724916)
			(end 1.1049 0.724916)
			(stroke
				(width 0.1)
				(type default)
			)
			(layer "B.Fab")
		)
		(fp_line
			(start 1.1049 0.724916)
			(end -1.1049 0.724916)
			(stroke
				(width 0.1)
				(type default)
			)
			(layer "B.Fab")
		)
		(pad "1" smd rect
			(at 0.889 0)
			(size 1.016 1.27)
			(layers "B.Cu" "B.Mask" "B.Paste")
			(net "PVCCIN_CPU1")
		)
		(pad "2" smd rect
			(at -0.889 0)
			(size 1.016 1.27)
			(layers "B.Cu" "B.Mask" "B.Paste")
			(net "GND")
		)
	)
	(footprint ""
		(layer "B.Cu")
		(at 343.524332 -324.873366 -90)
		(property "Reference" "PC314_P0_1"
			(at 0 0 90)
			(layer "B.SilkS")
			(hide yes)
			(effects
				(font
					(size 1.27 1.27)
				)
				(justify mirror)
			)
		)
		(property "Value" ""
			(at 0 0 90)
			(layer "B.Fab")
			(effects
				(font
					(size 1.27 1.27)
				)
				(justify mirror)
			)
		)
		(duplicate_pad_numbers_are_jumpers no)
		(fp_line
			(start -1.524 0.762)
			(end 1.524 0.762)
			(stroke
				(width 0.1524)
				(type default)
			)
			(layer "B.SilkS")
		)
		(fp_line
			(start 1.524 0.762)
			(end 1.524 -0.762)
			(stroke
				(width 0.1524)
				(type default)
			)
			(layer "B.SilkS")
		)
		(fp_line
			(start -1.524 -0.762)
			(end -1.524 0.762)
			(stroke
				(width 0.1524)
				(type default)
			)
			(layer "B.SilkS")
		)
		(fp_line
			(start 1.524 -0.762)
			(end -1.524 -0.762)
			(stroke
				(width 0.1524)
				(type default)
			)
			(layer "B.SilkS")
		)
		(fp_line
			(start -1.1049 0.724916)
			(end -1.1049 -0.724916)
			(stroke
				(width 0.1)
				(type default)
			)
			(layer "B.Fab")
		)
		(fp_line
			(start 1.1049 0.724916)
			(end -1.1049 0.724916)
			(stroke
				(width 0.1)
				(type default)
			)
			(layer "B.Fab")
		)
		(fp_line
			(start -1.1049 -0.724916)
			(end 1.1049 -0.724916)
			(stroke
				(width 0.1)
				(type default)
			)
			(layer "B.Fab")
		)
		(fp_line
			(start 1.1049 -0.724916)
			(end 1.1049 0.724916)
			(stroke
				(width 0.1)
				(type default)
			)
			(layer "B.Fab")
		)
		(pad "1" smd rect
			(at 0.889 0 270)
			(size 1.016 1.27)
			(layers "B.Cu" "B.Mask" "B.Paste")
			(net "PVCCIN_CPU0")
		)
		(pad "2" smd rect
			(at -0.889 0 270)
			(size 1.016 1.27)
			(layers "B.Cu" "B.Mask" "B.Paste")
			(net "GND")
		)
	)
	(footprint ""
		(layer "B.Cu")
		(at 175.355758 -112.175544 180)
		(property "Reference" "C1914"
			(at 0 0 0)
			(layer "B.SilkS")
			(hide yes)
			(effects
				(font
					(size 1.27 1.27)
				)
				(justify mirror)
			)
		)
		(property "Value" ""
			(at 0 0 0)
			(layer "B.Fab")
			(effects
				(font
					(size 1.27 1.27)
				)
				(justify mirror)
			)
		)
		(duplicate_pad_numbers_are_jumpers no)
		(fp_line
			(start 0.69215 0.2921)
			(end 0.69215 -0.2921)
			(stroke
				(width 0.1524)
				(type default)
			)
			(layer "B.SilkS")
		)
		(fp_line
			(start 0.69215 -0.2921)
			(end -0.69215 -0.2921)
			(stroke
				(width 0.1524)
				(type default)
			)
			(layer "B.SilkS")
		)
		(fp_line
			(start -0.69215 0.2921)
			(end 0.69215 0.2921)
			(stroke
				(width 0.1524)
				(type default)
			)
			(layer "B.SilkS")
		)
		(fp_line
			(start -0.69215 -0.2921)
			(end -0.69215 0.2921)
			(stroke
				(width 0.1524)
				(type default)
			)
			(layer "B.SilkS")
		)
		(fp_line
			(start 0.51435 0.2794)
			(end 0.51435 -0.2794)
			(stroke
				(width 0.1)
				(type default)
			)
			(layer "B.Fab")
		)
		(fp_line
			(start 0.51435 -0.2794)
			(end -0.51435 -0.2794)
			(stroke
				(width 0.1)
				(type default)
			)
			(layer "B.Fab")
		)
		(fp_line
			(start -0.51435 0.2794)
			(end 0.51435 0.2794)
			(stroke
				(width 0.1)
				(type default)
			)
			(layer "B.Fab")
		)
		(fp_line
			(start -0.51435 -0.2794)
			(end -0.51435 0.2794)
			(stroke
				(width 0.1)
				(type default)
			)
			(layer "B.Fab")
		)
		(pad "1" smd circle
			(at 0.40005 0)
			(size 0 0)
			(layers "B.Cu" "B.Mask" "B.Paste")
			(net "P3V3_AUX_FPGA_VCCIO0")
		)
		(pad "2" smd circle
			(at -0.40005 0)
			(size 0 0)
			(layers "B.Cu" "B.Mask" "B.Paste")
			(net "GND")
		)
		(zone
			(layer "B.Cu")
			(hatch none 0.5)
			(connect_pads
				(clearance 0)
			)
			(min_thickness 0.25)
			(keepout
				(tracks not_allowed)
				(vias allowed)
				(pads allowed)
				(copperpour not_allowed)
				(footprints allowed)
			)
			(placement
				(enabled no)
				(sheetname "")
			)
			(fill
				(thermal_gap 0.5)
				(thermal_bridge_width 0.5)
				(island_removal_mode 0)
			)
			(polygon
				(pts
					(xy 175.165258 -112.263174) (xy 175.256698 -112.32134) (xy 175.456088 -112.32134) (xy 175.546258 -112.263174)
					(xy 175.546258 -112.087914) (xy 175.456088 -112.029494) (xy 175.256698 -112.029494) (xy 175.165258 -112.08766)
				)
			)
		)
	)
	(footprint ""
		(layer "B.Cu")
		(at 175.355758 -114.575336 180)
		(property "Reference" "C1932"
			(at 0 0 0)
			(layer "B.SilkS")
			(hide yes)
			(effects
				(font
					(size 1.27 1.27)
				)
				(justify mirror)
			)
		)
		(property "Value" ""
			(at 0 0 0)
			(layer "B.Fab")
			(effects
				(font
					(size 1.27 1.27)
				)
				(justify mirror)
			)
		)
		(duplicate_pad_numbers_are_jumpers no)
		(fp_line
			(start 0.69215 0.2921)
			(end 0.69215 -0.2921)
			(stroke
				(width 0.1524)
				(type default)
			)
			(layer "B.SilkS")
		)
		(fp_line
			(start 0.69215 -0.2921)
			(end -0.69215 -0.2921)
			(stroke
				(width 0.1524)
				(type default)
			)
			(layer "B.SilkS")
		)
		(fp_line
			(start -0.69215 0.2921)
			(end 0.69215 0.2921)
			(stroke
				(width 0.1524)
				(type default)
			)
			(layer "B.SilkS")
		)
		(fp_line
			(start -0.69215 -0.2921)
			(end -0.69215 0.2921)
			(stroke
				(width 0.1524)
				(type default)
			)
			(layer "B.SilkS")
		)
		(fp_line
			(start 0.51435 0.2794)
			(end 0.51435 -0.2794)
			(stroke
				(width 0.1)
				(type default)
			)
			(layer "B.Fab")
		)
		(fp_line
			(start 0.51435 -0.2794)
			(end -0.51435 -0.2794)
			(stroke
				(width 0.1)
				(type default)
			)
			(layer "B.Fab")
		)
		(fp_line
			(start -0.51435 0.2794)
			(end 0.51435 0.2794)
			(stroke
				(width 0.1)
				(type default)
			)
			(layer "B.Fab")
		)
		(fp_line
			(start -0.51435 -0.2794)
			(end -0.51435 0.2794)
			(stroke
				(width 0.1)
				(type default)
			)
			(layer "B.Fab")
		)
		(pad "1" smd circle
			(at 0.40005 0)
			(size 0 0)
			(layers "B.Cu" "B.Mask" "B.Paste")
			(net "P3V3_AUX_FPGA_VCCIO0")
		)
		(pad "2" smd circle
			(at -0.40005 0)
			(size 0 0)
			(layers "B.Cu" "B.Mask" "B.Paste")
			(net "GND")
		)
		(zone
			(layer "B.Cu")
			(hatch none 0.5)
			(connect_pads
				(clearance 0)
			)
			(min_thickness 0.25)
			(keepout
				(tracks not_allowed)
				(vias allowed)
				(pads allowed)
				(copperpour not_allowed)
				(footprints allowed)
			)
			(placement
				(enabled no)
				(sheetname "")
			)
			(fill
				(thermal_gap 0.5)
				(thermal_bridge_width 0.5)
				(island_removal_mode 0)
			)
			(polygon
				(pts
					(xy 175.165258 -114.662966) (xy 175.256698 -114.721132) (xy 175.456088 -114.721132) (xy 175.546258 -114.662966)
					(xy 175.546258 -114.487706) (xy 175.456088 -114.429286) (xy 175.256698 -114.429286) (xy 175.165258 -114.487452)
				)
			)
		)
	)
	(footprint ""
		(layer "B.Cu")
		(at 97.748598 -324.753986 -90)
		(property "Reference" "PC578_P1_1"
			(at 0 0 90)
			(layer "B.SilkS")
			(hide yes)
			(effects
				(font
					(size 1.27 1.27)
				)
				(justify mirror)
			)
		)
		(property "Value" ""
			(at 0 0 90)
			(layer "B.Fab")
			(effects
				(font
					(size 1.27 1.27)
				)
				(justify mirror)
			)
		)
		(duplicate_pad_numbers_are_jumpers no)
		(fp_line
			(start -1.524 0.762)
			(end 1.524 0.762)
			(stroke
				(width 0.1524)
				(type default)
			)
			(layer "B.SilkS")
		)
		(fp_line
			(start 1.524 0.762)
			(end 1.524 -0.762)
			(stroke
				(width 0.1524)
				(type default)
			)
			(layer "B.SilkS")
		)
		(fp_line
			(start -1.524 -0.762)
			(end -1.524 0.762)
			(stroke
				(width 0.1524)
				(type default)
			)
			(layer "B.SilkS")
		)
		(fp_line
			(start 1.524 -0.762)
			(end -1.524 -0.762)
			(stroke
				(width 0.1524)
				(type default)
			)
			(layer "B.SilkS")
		)
		(fp_line
			(start -1.1049 0.724916)
			(end -1.1049 -0.724916)
			(stroke
				(width 0.1)
				(type default)
			)
			(layer "B.Fab")
		)
		(fp_line
			(start 1.1049 0.724916)
			(end -1.1049 0.724916)
			(stroke
				(width 0.1)
				(type default)
			)
			(layer "B.Fab")
		)
		(fp_line
			(start -1.1049 -0.724916)
			(end 1.1049 -0.724916)
			(stroke
				(width 0.1)
				(type default)
			)
			(layer "B.Fab")
		)
		(fp_line
			(start 1.1049 -0.724916)
			(end 1.1049 0.724916)
			(stroke
				(width 0.1)
				(type default)
			)
			(layer "B.Fab")
		)
		(pad "1" smd rect
			(at 0.889 0 270)
			(size 1.016 1.27)
			(layers "B.Cu" "B.Mask" "B.Paste")
			(net "PVCCIN_CPU1")
		)
		(pad "2" smd rect
			(at -0.889 0 270)
			(size 1.016 1.27)
			(layers "B.Cu" "B.Mask" "B.Paste")
			(net "GND")
		)
	)
	(footprint ""
		(layer "B.Cu")
		(at 285.462726 -193.691256 -90)
		(property "Reference" "R836"
			(at 0 0 90)
			(layer "B.SilkS")
			(hide yes)
			(effects
				(font
					(size 1.27 1.27)
				)
				(justify mirror)
			)
		)
		(property "Value" ""
			(at 0 0 90)
			(layer "B.Fab")
			(effects
				(font
					(size 1.27 1.27)
				)
				(justify mirror)
			)
		)
		(duplicate_pad_numbers_are_jumpers no)
		(fp_line
			(start -0.7874 0.4064)
			(end 0.7874 0.4064)
			(stroke
				(width 0.1524)
				(type default)
			)
			(layer "B.SilkS")
		)
		(fp_line
			(start 0.7874 0.4064)
			(end 0.7874 -0.4064)
			(stroke
				(width 0.1524)
				(type default)
			)
			(layer "B.SilkS")
		)
		(fp_line
			(start -0.7874 -0.4064)
			(end -0.7874 0.4064)
			(stroke
				(width 0.1524)
				(type default)
			)
			(layer "B.SilkS")
		)
		(fp_line
			(start 0.7874 -0.4064)
			(end -0.7874 -0.4064)
			(stroke
				(width 0.1524)
				(type default)
			)
			(layer "B.SilkS")
		)
		(fp_line
			(start -0.67945 0.3048)
			(end -0.120396 0.3048)
			(stroke
				(width 0.1)
				(type default)
			)
			(layer "B.Fab")
		)
		(fp_line
			(start -0.120396 0.3048)
			(end -0.120396 0.2794)
			(stroke
				(width 0.1)
				(type default)
			)
			(layer "B.Fab")
		)
		(fp_line
			(start 0.12065 0.3048)
			(end 0.67945 0.3048)
			(stroke
				(width 0.1)
				(type default)
			)
			(layer "B.Fab")
		)
		(fp_line
			(start 0.67945 0.3048)
			(end 0.67945 -0.305054)
			(stroke
				(width 0.1)
				(type default)
			)
			(layer "B.Fab")
		)
		(fp_line
			(start -0.120396 0.2794)
			(end 0.12065 0.2794)
			(stroke
				(width 0.1)
				(type default)
			)
			(layer "B.Fab")
		)
		(fp_line
			(start 0.12065 0.2794)
			(end 0.12065 0.3048)
			(stroke
				(width 0.1)
				(type default)
			)
			(layer "B.Fab")
		)
		(fp_line
			(start -0.12065 -0.2794)
			(end -0.12065 -0.3048)
			(stroke
				(width 0.1)
				(type default)
			)
			(layer "B.Fab")
		)
		(fp_line
			(start 0.12065 -0.2794)
			(end -0.12065 -0.2794)
			(stroke
				(width 0.1)
				(type default)
			)
			(layer "B.Fab")
		)
		(fp_line
			(start -0.67945 -0.3048)
			(end -0.67945 0.3048)
			(stroke
				(width 0.1)
				(type default)
			)
			(layer "B.Fab")
		)
		(fp_line
			(start -0.12065 -0.3048)
			(end -0.67945 -0.3048)
			(stroke
				(width 0.1)
				(type default)
			)
			(layer "B.Fab")
		)
		(fp_line
			(start 0.12065 -0.305054)
			(end 0.12065 -0.2794)
			(stroke
				(width 0.1)
				(type default)
			)
			(layer "B.Fab")
		)
		(fp_line
			(start 0.67945 -0.305054)
			(end 0.12065 -0.305054)
			(stroke
				(width 0.1)
				(type default)
			)
			(layer "B.Fab")
		)
		(pad "1" smd circle
			(at 0.40005 0 90)
			(size 0 0)
			(layers "B.Cu" "B.Mask" "B.Paste")
			(net "RST_PLD_CPU0_DRAM_AB_N")
		)
		(pad "2" smd circle
			(at -0.40005 0 90)
			(size 0 0)
			(layers "B.Cu" "B.Mask" "B.Paste")
			(net "RST_M_AB_CPU0_FPGA_N")
		)
	)
)
